# S9S_MB_2U (Grand Teton) — schematic netlist excerpt (pin names and nets, part order shuffled) for the footprints in the layout excerpt that follows; sources: Cadence DE-HDL packaged netlist, KiCad conversion of 03242023_DA0F0TMBIJ0_F0T_Motherboard_J_brd_V01_OCP.brd

R318  Q_RES  10K 1% CHIP  pkg 0402LF  page 229 : A = FM_SPD_REMOTE_EN ; B = GND
R3203  Q_RES  33.2 1% CHIP  pkg 0402LF  page 160 : A = OCP_V3_2_AUX_PWR_EN ; B = OCP_V3_2_AUX_PWR_EN_R1

(kicad_pcb
	(version 20260206)
	(generator "pcbnew")
	(generator_version "10.0")
	(general
		(thickness 1.6)
		(legacy_teardrops no)
	)
	(paper "A4")
	(title_block
		(title "03242023_DA0F0TMBIJ0_F0T_Motherboard_J_brd_V01_OCP.brd")
		(comment 1 "Grand Teton / footprints 4934-4935 of 6105")
	)
	(layers
		(0 "F.Cu" signal "TOP")
		(4 "In1.Cu" signal "GND")
		(6 "In2.Cu" signal "IN1")
		(8 "In3.Cu" signal "GND1")
		(10 "In4.Cu" signal "IN2")
		(12 "In5.Cu" signal "GND2")
		(14 "In6.Cu" signal "IN3")
		(16 "In7.Cu" signal "GND3")
		(18 "In8.Cu" signal "VCC")
		(20 "In9.Cu" signal "VCC1")
		(22 "In10.Cu" signal "GND4")
		(24 "In11.Cu" signal "IN4")
		(26 "In12.Cu" signal "GND5")
		(28 "In13.Cu" signal "IN5")
		(30 "In14.Cu" signal "GND6")
		(32 "In15.Cu" signal "IN6")
		(34 "In16.Cu" signal "GND7")
		(2 "B.Cu" signal "BOTTOM")
		(9 "F.Adhes" user "F.Adhesive")
		(11 "B.Adhes" user "B.Adhesive")
		(13 "F.Paste" user "Package Geometry/Pastemask Top")
		(15 "B.Paste" user "Package Geometry/Pastemask Bottom")
		(5 "F.SilkS" user "Ref Des/Silkscreen Top")
		(7 "B.SilkS" user "Ref Des/Silkscreen Bottom")
		(1 "F.Mask" user "Board Geometry/Soldermask Top")
		(3 "B.Mask" user "Board Geometry/Soldermask Bottom")
		(17 "Dwgs.User" user "User.Drawings")
		(19 "Cmts.User" user "User.Comments")
		(21 "Eco1.User" user "User.Eco1")
		(23 "Eco2.User" user "User.Eco2")
		(25 "Edge.Cuts" user "Board Geometry/Outline")
		(27 "Margin" user)
		(31 "F.CrtYd" user "Package Geometry/Place Bound Top")
		(29 "B.CrtYd" user "Package Geometry/Place Bound Bottom")
		(35 "F.Fab" user "Ref Des/Assembly Top")
		(33 "B.Fab" user "Ref Des/Assembly Bottom")
	)
	(footprint ""
		(layer "B.Cu")
		(at 160.83788 -107.025948 180)
		(property "Reference" "R3203"
			(at 0 0 0)
			(layer "B.SilkS")
			(hide yes)
			(effects
				(font
					(size 1.27 1.27)
				)
				(justify mirror)
			)
		)
		(property "Value" ""
			(at 0 0 0)
			(layer "B.Fab")
			(effects
				(font
					(size 1.27 1.27)
				)
				(justify mirror)
			)
		)
		(duplicate_pad_numbers_are_jumpers no)
		(fp_line
			(start 0.7874 0.4064)
			(end 0.7874 -0.4064)
			(stroke
				(width 0.1524)
				(type default)
			)
			(layer "B.SilkS")
		)
		(fp_line
			(start 0.7874 -0.4064)
			(end -0.7874 -0.4064)
			(stroke
				(width 0.1524)
				(type default)
			)
			(layer "B.SilkS")
		)
		(fp_line
			(start -0.7874 0.4064)
			(end 0.7874 0.4064)
			(stroke
				(width 0.1524)
				(type default)
			)
			(layer "B.SilkS")
		)
		(fp_line
			(start -0.7874 -0.4064)
			(end -0.7874 0.4064)
			(stroke
				(width 0.1524)
				(type default)
			)
			(layer "B.SilkS")
		)
		(fp_line
			(start 0.67945 0.3048)
			(end 0.67945 -0.305054)
			(stroke
				(width 0.1)
				(type default)
			)
			(layer "B.Fab")
		)
		(fp_line
			(start 0.67945 -0.305054)
			(end 0.12065 -0.305054)
			(stroke
				(width 0.1)
				(type default)
			)
			(layer "B.Fab")
		)
		(fp_line
			(start 0.12065 0.3048)
			(end 0.67945 0.3048)
			(stroke
				(width 0.1)
				(type default)
			)
			(layer "B.Fab")
		)
		(fp_line
			(start 0.12065 0.2794)
			(end 0.12065 0.3048)
			(stroke
				(width 0.1)
				(type default)
			)
			(layer "B.Fab")
		)
		(fp_line
			(start 0.12065 -0.2794)
			(end -0.12065 -0.2794)
			(stroke
				(width 0.1)
				(type default)
			)
			(layer "B.Fab")
		)
		(fp_line
			(start 0.12065 -0.305054)
			(end 0.12065 -0.2794)
			(stroke
				(width 0.1)
				(type default)
			)
			(layer "B.Fab")
		)
		(fp_line
			(start -0.120396 0.3048)
			(end -0.120396 0.2794)
			(stroke
				(width 0.1)
				(type default)
			)
			(layer "B.Fab")
		)
		(fp_line
			(start -0.120396 0.2794)
			(end 0.12065 0.2794)
			(stroke
				(width 0.1)
				(type default)
			)
			(layer "B.Fab")
		)
		(fp_line
			(start -0.12065 -0.2794)
			(end -0.12065 -0.3048)
			(stroke
				(width 0.1)
				(type default)
			)
			(layer "B.Fab")
		)
		(fp_line
			(start -0.12065 -0.3048)
			(end -0.67945 -0.3048)
			(stroke
				(width 0.1)
				(type default)
			)
			(layer "B.Fab")
		)
		(fp_line
			(start -0.67945 0.3048)
			(end -0.120396 0.3048)
			(stroke
				(width 0.1)
				(type default)
			)
			(layer "B.Fab")
		)
		(fp_line
			(start -0.67945 -0.3048)
			(end -0.67945 0.3048)
			(stroke
				(width 0.1)
				(type default)
			)
			(layer "B.Fab")
		)
		(pad "1" smd circle
			(at 0.40005 0)
			(size 0 0)
			(layers "B.Cu" "B.Mask" "B.Paste")
			(net "OCP_V3_2_AUX_PWR_EN")
		)
		(pad "2" smd circle
			(at -0.40005 0)
			(size 0 0)
			(layers "B.Cu" "B.Mask" "B.Paste")
			(net "OCP_V3_2_AUX_PWR_EN_R1")
		)
	)
	(footprint ""
		(layer "B.Cu")
		(at 292.980618 -149.992588 90)
		(property "Reference" "R318"
			(at 0 0 90)
			(layer "B.SilkS")
			(hide yes)
			(effects
				(font
					(size 1.27 1.27)
				)
				(justify mirror)
			)
		)
		(property "Value" ""
			(at 0 0 90)
			(layer "B.Fab")
			(effects
				(font
					(size 1.27 1.27)
				)
				(justify mirror)
			)
		)
		(duplicate_pad_numbers_are_jumpers no)
		(fp_line
			(start 0.7874 -0.4064)
			(end -0.7874 -0.4064)
			(stroke
				(width 0.1524)
				(type default)
			)
			(layer "B.SilkS")
		)
		(fp_line
			(start -0.7874 -0.4064)
			(end -0.7874 0.4064)
			(stroke
				(width 0.1524)
				(type default)
			)
			(layer "B.SilkS")
		)
		(fp_line
			(start 0.7874 0.4064)
			(end 0.7874 -0.4064)
			(stroke
				(width 0.1524)
				(type default)
			)
			(layer "B.SilkS")
		)
		(fp_line
			(start -0.7874 0.4064)
			(end 0.7874 0.4064)
			(stroke
				(width 0.1524)
				(type default)
			)
			(layer "B.SilkS")
		)
		(fp_line
			(start 0.67945 -0.305054)
			(end 0.12065 -0.305054)
			(stroke
				(width 0.1)
				(type default)
			)
			(layer "B.Fab")
		)
		(fp_line
			(start 0.12065 -0.305054)
			(end 0.12065 -0.2794)
			(stroke
				(width 0.1)
				(type default)
			)
			(layer "B.Fab")
		)
		(fp_line
			(start -0.12065 -0.3048)
			(end -0.67945 -0.3048)
			(stroke
				(width 0.1)
				(type default)
			)
			(layer "B.Fab")
		)
		(fp_line
			(start -0.67945 -0.3048)
			(end -0.67945 0.3048)
			(stroke
				(width 0.1)
				(type default)
			)
			(layer "B.Fab")
		)
		(fp_line
			(start 0.12065 -0.2794)
			(end -0.12065 -0.2794)
			(stroke
				(width 0.1)
				(type default)
			)
			(layer "B.Fab")
		)
		(fp_line
			(start -0.12065 -0.2794)
			(end -0.12065 -0.3048)
			(stroke
				(width 0.1)
				(type default)
			)
			(layer "B.Fab")
		)
		(fp_line
			(start 0.12065 0.2794)
			(end 0.12065 0.3048)
			(stroke
				(width 0.1)
				(type default)
			)
			(layer "B.Fab")
		)
		(fp_line
			(start -0.120396 0.2794)
			(end 0.12065 0.2794)
			(stroke
				(width 0.1)
				(type default)
			)
			(layer "B.Fab")
		)
		(fp_line
			(start 0.67945 0.3048)
			(end 0.67945 -0.305054)
			(stroke
				(width 0.1)
				(type default)
			)
			(layer "B.Fab")
		)
		(fp_line
			(start 0.12065 0.3048)
			(end 0.67945 0.3048)
			(stroke
				(width 0.1)
				(type default)
			)
			(layer "B.Fab")
		)
		(fp_line
			(start -0.120396 0.3048)
			(end -0.120396 0.2794)
			(stroke
				(width 0.1)
				(type default)
			)
			(layer "B.Fab")
		)
		(fp_line
			(start -0.67945 0.3048)
			(end -0.120396 0.3048)
			(stroke
				(width 0.1)
				(type default)
			)
			(layer "B.Fab")
		)
		(pad "1" smd circle
			(at 0.40005 0 270)
			(size 0 0)
			(layers "B.Cu" "B.Mask" "B.Paste")
			(net "FM_SPD_REMOTE_EN")
		)
		(pad "2" smd circle
			(at -0.40005 0 270)
			(size 0 0)
			(layers "B.Cu" "B.Mask" "B.Paste")
			(net "GND")
		)
	)
)
